(kicad_pcb
	(version 20260206)
	(generator "pcbnew")
	(generator_version "10.0")
	(general
		(thickness 1.6)
		(legacy_teardrops no)
	)
	(paper "A4")
	(title_block
		(title "v1-chassis-manager — T6M_CM_d_v01_1031_1645.brd")
		(comment 1 "Open CloudServer (Microsoft) / footprints 382-387 of 2512")
	)
	(layers
		(0 "F.Cu" signal "TOP")
		(4 "In1.Cu" signal "GND1")
		(6 "In2.Cu" signal "IN1")
		(8 "In3.Cu" signal "VCC1")
		(10 "In4.Cu" signal "VCC2")
		(12 "In5.Cu" signal "GND2")
		(14 "In6.Cu" signal "IN2")
		(16 "In7.Cu" signal "IN3")
		(18 "In8.Cu" signal "GND3")
		(2 "B.Cu" signal "BOTTOM")
		(9 "F.Adhes" user "F.Adhesive")
		(11 "B.Adhes" user "B.Adhesive")
		(13 "F.Paste" user "Package Geometry/Pastemask Top")
		(15 "B.Paste" user "Package Geometry/Pastemask Bottom")
		(5 "F.SilkS" user "Ref Des/Silkscreen Top")
		(7 "B.SilkS" user "Ref Des/Silkscreen Bottom")
		(1 "F.Mask" user "Board Geometry/Soldermask Top")
		(3 "B.Mask" user "Board Geometry/Soldermask Bottom")
		(17 "Dwgs.User" user "User.Drawings")
		(19 "Cmts.User" user "User.Comments")
		(21 "Eco1.User" user "User.Eco1")
		(23 "Eco2.User" user "User.Eco2")
		(25 "Edge.Cuts" user "Board Geometry/Outline")
		(27 "Margin" user)
		(31 "F.CrtYd" user "Package Geometry/Place Bound Top")
		(29 "B.CrtYd" user "Package Geometry/Place Bound Bottom")
		(35 "F.Fab" user "Ref Des/Assembly Top")
		(33 "B.Fab" user "Ref Des/Assembly Bottom")
	)
	(footprint ""
		(layer "F.Cu")
		(at 162.696906 -118.335552 180)
		(property "Reference" "R134"
			(at 4.487672 -0.390398 0)
			(unlocked yes)
			(layer "F.SilkS")
			(effects
				(font
					(size 0.7874 0.5842)
					(thickness 0.1524)
				)
				(justify left)
			)
		)
		(property "Value" ""
			(at 0 0 180)
			(layer "F.Fab")
			(effects
				(font
					(size 1.27 1.27)
				)
			)
		)
		(duplicate_pad_numbers_are_jumpers no)
		(fp_line
			(start 0.7874 0.4064)
			(end -0.7874 0.4064)
			(stroke
				(width 0.1524)
				(type default)
			)
			(layer "F.SilkS")
		)
		(fp_line
			(start 0.7874 -0.4064)
			(end 0.7874 0.4064)
			(stroke
				(width 0.1524)
				(type default)
			)
			(layer "F.SilkS")
		)
		(fp_line
			(start -0.7874 0.4064)
			(end -0.7874 -0.4064)
			(stroke
				(width 0.1524)
				(type default)
			)
			(layer "F.SilkS")
		)
		(fp_line
			(start -0.7874 -0.4064)
			(end 0.7874 -0.4064)
			(stroke
				(width 0.1524)
				(type default)
			)
			(layer "F.SilkS")
		)
		(fp_poly
			(pts
				(xy -0.508 0.2794) (xy -0.508 0.2286) (xy -0.635 0.2286) (xy -0.635 -0.254) (xy -0.5334 -0.254)
				(xy -0.5334 -0.2794) (xy 0.5334 -0.2794) (xy 0.5334 -0.254) (xy 0.635 -0.254) (xy 0.635 0.254) (xy 0.5334 0.254)
				(xy 0.5334 0.2794)
			)
			(stroke
				(width 0)
				(type default)
			)
			(fill no)
			(layer "F.CrtYd")
		)
		(pad "1" smd rect
			(at 0.40005 0 180)
			(size 0.4572 0.508)
			(layers "F.Cu" "F.Mask" "F.Paste")
			(net "GND")
		)
		(pad "2" smd rect
			(at -0.40005 0 180)
			(size 0.4572 0.508)
			(layers "F.Cu" "F.Mask" "F.Paste")
			(net "FM_CPU_NODE1_RSTWARN")
		)
	)
	(footprint ""
		(layer "F.Cu")
		(at 69.273166 -96.709992 90)
		(property "Reference" "R69"
			(at -54.98719 28.346146 90)
			(unlocked yes)
			(layer "F.SilkS")
			(effects
				(font
					(size 0.7874 0.5842)
					(thickness 0.1524)
				)
				(justify left)
			)
		)
		(property "Value" ""
			(at 0 0 90)
			(layer "F.Fab")
			(effects
				(font
					(size 1.27 1.27)
				)
			)
		)
		(duplicate_pad_numbers_are_jumpers no)
		(fp_line
			(start 0.7874 -0.4064)
			(end 0.7874 0.4064)
			(stroke
				(width 0.1524)
				(type default)
			)
			(layer "F.SilkS")
		)
		(fp_line
			(start -0.7874 -0.4064)
			(end 0.7874 -0.4064)
			(stroke
				(width 0.1524)
				(type default)
			)
			(layer "F.SilkS")
		)
		(fp_line
			(start 0.7874 0.4064)
			(end -0.7874 0.4064)
			(stroke
				(width 0.1524)
				(type default)
			)
			(layer "F.SilkS")
		)
		(fp_line
			(start -0.7874 0.4064)
			(end -0.7874 -0.4064)
			(stroke
				(width 0.1524)
				(type default)
			)
			(layer "F.SilkS")
		)
		(fp_poly
			(pts
				(xy -0.508 0.2794) (xy -0.508 0.2286) (xy -0.635 0.2286) (xy -0.635 -0.254) (xy -0.5334 -0.254)
				(xy -0.5334 -0.2794) (xy 0.5334 -0.2794) (xy 0.5334 -0.254) (xy 0.635 -0.254) (xy 0.635 0.254) (xy 0.5334 0.254)
				(xy 0.5334 0.2794)
			)
			(stroke
				(width 0)
				(type default)
			)
			(fill no)
			(layer "F.CrtYd")
		)
		(pad "1" smd rect
			(at 0.40005 0 90)
			(size 0.4572 0.508)
			(layers "F.Cu" "F.Mask" "F.Paste")
			(net "SPC_CPU_NODE1_DTR_L")
		)
		(pad "2" smd rect
			(at -0.40005 0 90)
			(size 0.4572 0.508)
			(layers "F.Cu" "F.Mask" "F.Paste")
			(net "SPC_CPU_NODE1_DSR_L")
		)
	)
	(footprint ""
		(layer "F.Cu")
		(at 169.664888 -37.455856 90)
		(property "Reference" "L42"
			(at -3.408172 -2.057654 90)
			(unlocked yes)
			(layer "F.SilkS")
			(effects
				(font
					(size 0.7874 0.5842)
					(thickness 0.1524)
				)
				(justify left)
			)
		)
		(property "Value" ""
			(at 0 0 90)
			(layer "F.Fab")
			(effects
				(font
					(size 1.27 1.27)
				)
			)
		)
		(duplicate_pad_numbers_are_jumpers no)
		(fp_line
			(start 0.989838 -2.0066)
			(end 0.989838 2.0066)
			(stroke
				(width 0.1524)
				(type default)
			)
			(layer "F.SilkS")
		)
		(fp_line
			(start -1.015238 -2.0066)
			(end 0.989838 -2.0066)
			(stroke
				(width 0.1524)
				(type default)
			)
			(layer "F.SilkS")
		)
		(fp_line
			(start 0.989838 2.0066)
			(end -1.015238 2.0066)
			(stroke
				(width 0.1524)
				(type default)
			)
			(layer "F.SilkS")
		)
		(fp_line
			(start -1.015238 2.0066)
			(end -1.015238 -2.0066)
			(stroke
				(width 0.1524)
				(type default)
			)
			(layer "F.SilkS")
		)
		(fp_poly
			(pts
				(xy -0.899922 -1.700022) (xy -0.899922 1.700022) (xy -0.8636 1.700022) (xy -0.8636 1.9304) (xy -0.127 1.9304)
				(xy -0.127 1.700022) (xy 0.127 1.700022) (xy 0.127 1.9304) (xy 0.8636 1.9304) (xy 0.8636 1.700022)
				(xy 0.899922 1.700022) (xy 0.899922 -1.700022) (xy 0.8636 -1.700022) (xy 0.8636 -1.9304) (xy 0.127 -1.9304)
				(xy 0.127 -1.700022) (xy -0.127 -1.700022) (xy -0.127 -1.9304) (xy -0.8636 -1.9304) (xy -0.8636 -1.700022)
			)
			(stroke
				(width 0)
				(type default)
			)
			(fill no)
			(layer "F.CrtYd")
		)
		(fp_line
			(start 0.899922 -1.700022)
			(end 0.899922 1.700022)
			(stroke
				(width 0.1)
				(type default)
			)
			(layer "F.Fab")
		)
		(fp_line
			(start -0.899922 -1.700022)
			(end 0.899922 -1.700022)
			(stroke
				(width 0.1)
				(type default)
			)
			(layer "F.Fab")
		)
		(fp_line
			(start 0.899922 1.700022)
			(end -0.899922 1.700022)
			(stroke
				(width 0.1)
				(type default)
			)
			(layer "F.Fab")
		)
		(fp_line
			(start -0.899922 1.700022)
			(end -0.899922 -1.700022)
			(stroke
				(width 0.1)
				(type default)
			)
			(layer "F.Fab")
		)
		(pad "1" smd rect
			(at -0.499872 -1.400048 90)
			(size 0.6096 0.9144)
			(layers "F.Cu" "F.Mask" "F.Paste")
			(net "USB0_DN")
		)
		(pad "2" smd rect
			(at -0.499872 1.400048 90)
			(size 0.6096 0.9144)
			(layers "F.Cu" "F.Mask" "F.Paste")
			(net "USB0_L_DN")
		)
		(pad "3" smd rect
			(at 0.499872 1.400048 90)
			(size 0.6096 0.9144)
			(layers "F.Cu" "F.Mask" "F.Paste")
			(net "USB0_L_DP")
		)
		(pad "4" smd rect
			(at 0.499872 -1.400048 90)
			(size 0.6096 0.9144)
			(layers "F.Cu" "F.Mask" "F.Paste")
			(net "USB0_DP")
		)
	)
	(footprint ""
		(layer "F.Cu")
		(at 118.977918 -155.754578 180)
		(property "Reference" "R1059"
			(at 0.913638 2.237486 0)
			(unlocked yes)
			(layer "F.SilkS")
			(effects
				(font
					(size 0.635 0.4064)
					(thickness 0.1524)
				)
				(justify left)
			)
		)
		(property "Value" ""
			(at 0 0 180)
			(layer "F.Fab")
			(effects
				(font
					(size 1.27 1.27)
				)
			)
		)
		(duplicate_pad_numbers_are_jumpers no)
		(fp_line
			(start 0.7874 0.4064)
			(end -0.7874 0.4064)
			(stroke
				(width 0.1524)
				(type default)
			)
			(layer "F.SilkS")
		)
		(fp_line
			(start 0.7874 -0.4064)
			(end 0.7874 0.4064)
			(stroke
				(width 0.1524)
				(type default)
			)
			(layer "F.SilkS")
		)
		(fp_line
			(start -0.7874 0.4064)
			(end -0.7874 -0.4064)
			(stroke
				(width 0.1524)
				(type default)
			)
			(layer "F.SilkS")
		)
		(fp_line
			(start -0.7874 -0.4064)
			(end 0.7874 -0.4064)
			(stroke
				(width 0.1524)
				(type default)
			)
			(layer "F.SilkS")
		)
		(fp_poly
			(pts
				(xy -0.508 0.2794) (xy -0.508 0.2286) (xy -0.635 0.2286) (xy -0.635 -0.254) (xy -0.5334 -0.254)
				(xy -0.5334 -0.2794) (xy 0.5334 -0.2794) (xy 0.5334 -0.254) (xy 0.635 -0.254) (xy 0.635 0.254) (xy 0.5334 0.254)
				(xy 0.5334 0.2794)
			)
			(stroke
				(width 0)
				(type default)
			)
			(fill no)
			(layer "F.CrtYd")
		)
		(pad "1" smd rect
			(at 0.40005 0 180)
			(size 0.4572 0.508)
			(layers "F.Cu" "F.Mask" "F.Paste")
			(net "N52998261")
		)
		(pad "2" smd rect
			(at -0.40005 0 180)
			(size 0.4572 0.508)
			(layers "F.Cu" "F.Mask" "F.Paste")
			(net "P3V3_STB_NODE1")
		)
	)
	(footprint ""
		(layer "F.Cu")
		(at 22.15261 -69.986652 180)
		(property "Reference" "D7"
			(at -0.788162 2.805938 90)
			(unlocked yes)
			(layer "F.SilkS")
			(effects
				(font
					(size 0.7874 0.5842)
					(thickness 0.1524)
				)
			)
		)
		(property "Value" ""
			(at 0 0 180)
			(layer "F.Fab")
			(effects
				(font
					(size 1.27 1.27)
				)
			)
		)
		(duplicate_pad_numbers_are_jumpers no)
		(fp_line
			(start 1.519936 1.6002)
			(end -1.519936 1.6002)
			(stroke
				(width 0.1524)
				(type default)
			)
			(layer "F.SilkS")
		)
		(fp_line
			(start 1.519936 -1.6002)
			(end 1.519936 1.6002)
			(stroke
				(width 0.1524)
				(type default)
			)
			(layer "F.SilkS")
		)
		(fp_line
			(start -1.519936 1.6002)
			(end -1.519936 -1.5748)
			(stroke
				(width 0.1524)
				(type default)
			)
			(layer "F.SilkS")
		)
		(fp_line
			(start -1.519936 -1.6002)
			(end 1.519936 -1.6002)
			(stroke
				(width 0.1524)
				(type default)
			)
			(layer "F.SilkS")
		)
		(fp_poly
			(pts
				(xy -1.519936 0.700024) (xy -1.3716 0.700024) (xy -1.3716 1.4732) (xy -0.5334 1.4732) (xy -0.5334 0.700024)
				(xy 0.5334 0.700024) (xy 0.5334 1.4732) (xy 1.3716 1.4732) (xy 1.3716 0.700024) (xy 1.519936 0.700024)
				(xy 1.519936 -0.700024) (xy 0.4064 -0.700024) (xy 0.4064 -1.4732) (xy -0.4064 -1.4732) (xy -0.4064 -0.700024)
				(xy -1.519936 -0.700024)
			)
			(stroke
				(width 0)
				(type default)
			)
			(fill no)
			(layer "F.CrtYd")
		)
		(fp_line
			(start 1.519936 0.700024)
			(end -1.519936 0.700024)
			(stroke
				(width 0.1)
				(type default)
			)
			(layer "F.Fab")
		)
		(fp_line
			(start 1.519936 -0.700024)
			(end 1.519936 0.700024)
			(stroke
				(width 0.1)
				(type default)
			)
			(layer "F.Fab")
		)
		(fp_line
			(start -1.519936 0.700024)
			(end -1.519936 -0.700024)
			(stroke
				(width 0.1)
				(type default)
			)
			(layer "F.Fab")
		)
		(fp_line
			(start -1.519936 -0.700024)
			(end 1.519936 -0.700024)
			(stroke
				(width 0.1)
				(type default)
			)
			(layer "F.Fab")
		)
		(fp_text user "2"
			(at 1.78816 1.171956 0)
			(unlocked yes)
			(layer "F.SilkS")
			(effects
				(font
					(size 0.635 0.4064)
					(thickness 0.1524)
				)
			)
		)
		(fp_text user "3"
			(at 0.730758 -2.16662 0)
			(unlocked yes)
			(layer "F.SilkS")
			(effects
				(font
					(size 0.635 0.4064)
					(thickness 0.1524)
				)
			)
		)
		(fp_text user "1"
			(at -1.754378 0.227076 180)
			(unlocked yes)
			(layer "F.SilkS")
			(effects
				(font
					(size 0.635 0.4064)
					(thickness 0.1524)
				)
			)
		)
		(pad "1" smd rect
			(at -0.94996 0.999998 180)
			(size 0.8128 0.9144)
			(layers "F.Cu" "F.Mask" "F.Paste")
			(net "SMB_BMC_NODE1_DDC_CLK")
		)
		(pad "2" smd rect
			(at 0.94996 0.999998 180)
			(size 0.8128 0.9144)
			(layers "F.Cu" "F.Mask" "F.Paste")
			(net "Net_1679")
		)
		(pad "3" smd rect
			(at 0 -0.999998 180)
			(size 0.8128 0.9144)
			(layers "F.Cu" "F.Mask" "F.Paste")
			(net "I2C_VIDREAR_5V_SCL")
		)
	)
	(footprint ""
		(layer "F.Cu")
		(at 70.100698 -17.679416 90)
		(property "Reference" "C152"
			(at -4.786884 6.313678 90)
			(unlocked yes)
			(layer "F.SilkS")
			(effects
				(font
					(size 0.7874 0.5842)
					(thickness 0.1524)
				)
				(justify left)
			)
		)
		(property "Value" ""
			(at 0 0 90)
			(layer "F.Fab")
			(effects
				(font
					(size 1.27 1.27)
				)
			)
		)
		(duplicate_pad_numbers_are_jumpers no)
		(fp_line
			(start 0.7874 -0.4064)
			(end 0.7874 0.4064)
			(stroke
				(width 0.1524)
				(type default)
			)
			(layer "F.SilkS")
		)
		(fp_line
			(start -0.7874 -0.4064)
			(end 0.7874 -0.4064)
			(stroke
				(width 0.1524)
				(type default)
			)
			(layer "F.SilkS")
		)
		(fp_line
			(start 0 0.381)
			(end 0 -0.381)
			(stroke
				(width 0.1524)
				(type default)
			)
			(layer "F.SilkS")
		)
		(fp_line
			(start 0.7874 0.4064)
			(end -0.7874 0.4064)
			(stroke
				(width 0.1524)
				(type default)
			)
			(layer "F.SilkS")
		)
		(fp_line
			(start -0.7874 0.4064)
			(end -0.7874 -0.4064)
			(stroke
				(width 0.1524)
				(type default)
			)
			(layer "F.SilkS")
		)
		(fp_poly
			(pts
				(xy -0.5334 0.254) (xy -0.635 0.254) (xy -0.635 0.2286) (xy -0.635 -0.254) (xy -0.5334 -0.254) (xy -0.5334 -0.2794)
				(xy 0.5334 -0.2794) (xy 0.5334 -0.254) (xy 0.635 -0.254) (xy 0.635 0.254) (xy 0.5334 0.254) (xy 0.5334 0.2794)
				(xy -0.508 0.2794) (xy -0.5334 0.2794)
			)
			(stroke
				(width 0)
				(type default)
			)
			(fill no)
			(layer "F.CrtYd")
		)
		(pad "1" smd rect
			(at 0.40005 0 90)
			(size 0.4572 0.508)
			(layers "F.Cu" "F.Mask" "F.Paste")
			(net "PV_VDDR_NODE1")
		)
		(pad "2" smd rect
			(at -0.40005 0 90)
			(size 0.4572 0.508)
			(layers "F.Cu" "F.Mask" "F.Paste")
			(net "GND")
		)
	)
)
